(kicad_pcb
	(version 20260206)
	(generator "pcbnew")
	(generator_version "10.0")
	(general
		(thickness 1.6)
		(legacy_teardrops no)
	)
	(paper "A4")
	(title_block
		(title "v1-chassis-manager — T6M_CM_d_v01_1031_1645.brd")
		(comment 1 "Open CloudServer (Microsoft) / footprints 577-582 of 2512")
	)
	(layers
		(0 "F.Cu" signal "TOP")
		(4 "In1.Cu" signal "GND1")
		(6 "In2.Cu" signal "IN1")
		(8 "In3.Cu" signal "VCC1")
		(10 "In4.Cu" signal "VCC2")
		(12 "In5.Cu" signal "GND2")
		(14 "In6.Cu" signal "IN2")
		(16 "In7.Cu" signal "IN3")
		(18 "In8.Cu" signal "GND3")
		(2 "B.Cu" signal "BOTTOM")
		(9 "F.Adhes" user "F.Adhesive")
		(11 "B.Adhes" user "B.Adhesive")
		(13 "F.Paste" user "Package Geometry/Pastemask Top")
		(15 "B.Paste" user "Package Geometry/Pastemask Bottom")
		(5 "F.SilkS" user "Ref Des/Silkscreen Top")
		(7 "B.SilkS" user "Ref Des/Silkscreen Bottom")
		(1 "F.Mask" user "Board Geometry/Soldermask Top")
		(3 "B.Mask" user "Board Geometry/Soldermask Bottom")
		(17 "Dwgs.User" user "User.Drawings")
		(19 "Cmts.User" user "User.Comments")
		(21 "Eco1.User" user "User.Eco1")
		(23 "Eco2.User" user "User.Eco2")
		(25 "Edge.Cuts" user "Board Geometry/Outline")
		(27 "Margin" user)
		(31 "F.CrtYd" user "Package Geometry/Place Bound Top")
		(29 "B.CrtYd" user "Package Geometry/Place Bound Bottom")
		(35 "F.Fab" user "Ref Des/Assembly Top")
		(33 "B.Fab" user "Ref Des/Assembly Bottom")
	)
	(footprint ""
		(layer "F.Cu")
		(at 44.207176 -177.285904 180)
		(property "Reference" "C773"
			(at 0.978916 -132.638292 0)
			(unlocked yes)
			(layer "F.SilkS")
			(effects
				(font
					(size 0.7874 0.5842)
					(thickness 0.1524)
				)
				(justify left)
			)
		)
		(property "Value" ""
			(at 0 0 180)
			(layer "F.Fab")
			(effects
				(font
					(size 1.27 1.27)
				)
			)
		)
		(duplicate_pad_numbers_are_jumpers no)
		(fp_line
			(start 0.7874 0.4064)
			(end -0.7874 0.4064)
			(stroke
				(width 0.1524)
				(type default)
			)
			(layer "F.SilkS")
		)
		(fp_line
			(start 0.7874 -0.4064)
			(end 0.7874 0.4064)
			(stroke
				(width 0.1524)
				(type default)
			)
			(layer "F.SilkS")
		)
		(fp_line
			(start 0 0.381)
			(end 0 -0.381)
			(stroke
				(width 0.1524)
				(type default)
			)
			(layer "F.SilkS")
		)
		(fp_line
			(start -0.7874 0.4064)
			(end -0.7874 -0.4064)
			(stroke
				(width 0.1524)
				(type default)
			)
			(layer "F.SilkS")
		)
		(fp_line
			(start -0.7874 -0.4064)
			(end 0.7874 -0.4064)
			(stroke
				(width 0.1524)
				(type default)
			)
			(layer "F.SilkS")
		)
		(fp_poly
			(pts
				(xy -0.5334 0.254) (xy -0.635 0.254) (xy -0.635 0.2286) (xy -0.635 -0.254) (xy -0.5334 -0.254) (xy -0.5334 -0.2794)
				(xy 0.5334 -0.2794) (xy 0.5334 -0.254) (xy 0.635 -0.254) (xy 0.635 0.254) (xy 0.5334 0.254) (xy 0.5334 0.2794)
				(xy -0.508 0.2794) (xy -0.5334 0.2794)
			)
			(stroke
				(width 0)
				(type default)
			)
			(fill no)
			(layer "F.CrtYd")
		)
		(pad "1" smd rect
			(at 0.40005 0 180)
			(size 0.4572 0.508)
			(layers "F.Cu" "F.Mask" "F.Paste")
			(net "P12V_AUX")
		)
		(pad "2" smd rect
			(at -0.40005 0 180)
			(size 0.4572 0.508)
			(layers "F.Cu" "F.Mask" "F.Paste")
			(net "GND")
		)
	)
	(footprint ""
		(layer "F.Cu")
		(at 90.81262 -179.610512)
		(property "Reference" "R1252"
			(at 85.97392 76.338938 0)
			(unlocked yes)
			(layer "F.SilkS")
			(effects
				(font
					(size 0.7874 0.5842)
					(thickness 0.1524)
				)
				(justify left)
			)
		)
		(property "Value" ""
			(at 0 0 0)
			(layer "F.Fab")
			(effects
				(font
					(size 1.27 1.27)
				)
			)
		)
		(duplicate_pad_numbers_are_jumpers no)
		(fp_line
			(start -0.7874 -0.4064)
			(end 0.7874 -0.4064)
			(stroke
				(width 0.1524)
				(type default)
			)
			(layer "F.SilkS")
		)
		(fp_line
			(start -0.7874 0.4064)
			(end -0.7874 -0.4064)
			(stroke
				(width 0.1524)
				(type default)
			)
			(layer "F.SilkS")
		)
		(fp_line
			(start 0.7874 -0.4064)
			(end 0.7874 0.4064)
			(stroke
				(width 0.1524)
				(type default)
			)
			(layer "F.SilkS")
		)
		(fp_line
			(start 0.7874 0.4064)
			(end -0.7874 0.4064)
			(stroke
				(width 0.1524)
				(type default)
			)
			(layer "F.SilkS")
		)
		(fp_poly
			(pts
				(xy -0.508 0.2794) (xy -0.508 0.2286) (xy -0.635 0.2286) (xy -0.635 -0.254) (xy -0.5334 -0.254)
				(xy -0.5334 -0.2794) (xy 0.5334 -0.2794) (xy 0.5334 -0.254) (xy 0.635 -0.254) (xy 0.635 0.254) (xy 0.5334 0.254)
				(xy 0.5334 0.2794)
			)
			(stroke
				(width 0)
				(type default)
			)
			(fill no)
			(layer "F.CrtYd")
		)
		(pad "1" smd rect
			(at 0.40005 0)
			(size 0.4572 0.508)
			(layers "F.Cu" "F.Mask" "F.Paste")
			(net "CPLD_UART_RI_P4_N")
		)
		(pad "2" smd rect
			(at -0.40005 0)
			(size 0.4572 0.508)
			(layers "F.Cu" "F.Mask" "F.Paste")
			(net "P3V3_NODE1")
		)
	)
	(footprint ""
		(layer "F.Cu")
		(at 186.000136 -29.933392)
		(property "Reference" "CE2"
			(at -3.45948 0.831342 90)
			(unlocked yes)
			(layer "F.SilkS")
			(effects
				(font
					(size 0.7874 0.5842)
					(thickness 0.1524)
				)
				(justify left)
			)
		)
		(property "Value" ""
			(at 0 0 0)
			(layer "F.Fab")
			(effects
				(font
					(size 1.27 1.27)
				)
			)
		)
		(duplicate_pad_numbers_are_jumpers no)
		(fp_line
			(start -2.750058 -1.734058)
			(end -2.750058 2.750058)
			(stroke
				(width 0.1524)
				(type default)
			)
			(layer "F.SilkS")
		)
		(fp_line
			(start -2.750058 2.750058)
			(end 2.750058 2.750058)
			(stroke
				(width 0.1524)
				(type default)
			)
			(layer "F.SilkS")
		)
		(fp_line
			(start -1.734058 -2.750058)
			(end -2.750058 -1.734058)
			(stroke
				(width 0.1524)
				(type default)
			)
			(layer "F.SilkS")
		)
		(fp_line
			(start 1.734058 -2.750058)
			(end -1.734058 -2.750058)
			(stroke
				(width 0.1524)
				(type default)
			)
			(layer "F.SilkS")
		)
		(fp_line
			(start 2.750058 -1.734058)
			(end 1.734058 -2.750058)
			(stroke
				(width 0.1524)
				(type default)
			)
			(layer "F.SilkS")
		)
		(fp_line
			(start 2.750058 2.750058)
			(end 2.750058 -1.734058)
			(stroke
				(width 0.1524)
				(type default)
			)
			(layer "F.SilkS")
		)
		(fp_poly
			(pts
				(xy 2.750058 2.750058) (xy 0.8509 2.750058) (xy 0.8509 3.761994) (xy -0.8509 3.761994) (xy -0.8509 2.750058)
				(xy -2.750058 2.750058) (xy -2.750058 -2.750058) (xy -0.8509 -2.750058) (xy -0.8509 -3.761994) (xy 0.8509 -3.761994)
				(xy 0.8509 -2.750058) (xy 2.750058 -2.750058)
			)
			(stroke
				(width 0)
				(type default)
			)
			(fill no)
			(layer "F.CrtYd")
		)
		(fp_line
			(start -2.750058 -2.750058)
			(end -2.750058 2.750058)
			(stroke
				(width 0.1)
				(type default)
			)
			(layer "F.Fab")
		)
		(fp_line
			(start -2.750058 2.750058)
			(end 2.750058 2.750058)
			(stroke
				(width 0.1)
				(type default)
			)
			(layer "F.Fab")
		)
		(fp_line
			(start 2.750058 -2.750058)
			(end -2.750058 -2.750058)
			(stroke
				(width 0.1)
				(type default)
			)
			(layer "F.Fab")
		)
		(fp_line
			(start 2.750058 2.750058)
			(end 2.750058 -2.750058)
			(stroke
				(width 0.1)
				(type default)
			)
			(layer "F.Fab")
		)
		(fp_text user "1"
			(at -1.045464 -3.901186 0)
			(unlocked yes)
			(layer "F.SilkS")
			(effects
				(font
					(size 0.635 0.4064)
					(thickness 0.1524)
				)
			)
		)
		(fp_text user "2"
			(at -1.026922 4.12115 0)
			(unlocked yes)
			(layer "F.SilkS")
			(effects
				(font
					(size 0.635 0.4064)
					(thickness 0.1524)
				)
			)
		)
		(fp_text user "+"
			(at 2.151888 -4.699508 270)
			(unlocked yes)
			(layer "F.SilkS")
			(effects
				(font
					(size 1.6002 1.1938)
					(thickness 0.1524)
				)
				(justify left)
			)
		)
		(fp_text user "+"
			(at -0.8001 -4.89585 0)
			(unlocked yes)
			(layer "F.Fab")
			(effects
				(font
					(size 1.905 1.4224)
					(thickness 0.000001)
				)
				(justify left)
			)
		)
		(fp_text user "1"
			(at -0.041148 -4.064 90)
			(unlocked yes)
			(layer "F.Fab")
			(effects
				(font
					(size 0.7874 0.5842)
					(thickness 0.000001)
				)
			)
		)
		(fp_text user "2"
			(at -0.041148 4.2164 90)
			(unlocked yes)
			(layer "F.Fab")
			(effects
				(font
					(size 0.7874 0.5842)
					(thickness 0.000001)
				)
			)
		)
		(pad "1" smd oval
			(at 0 -2.199894 180)
			(size 1.6002 3.0226)
			(layers "F.Cu" "F.Mask" "F.Paste")
			(net "USBPWR_P0")
		)
		(pad "2" smd oval
			(at 0 2.199894 180)
			(size 1.6002 3.0226)
			(layers "F.Cu" "F.Mask" "F.Paste")
			(net "GND")
		)
	)
	(footprint ""
		(layer "F.Cu")
		(at 120.63476 -188.126624 -90)
		(property "Reference" "C742"
			(at -4.901184 0.175768 90)
			(unlocked yes)
			(layer "F.SilkS")
			(effects
				(font
					(size 0.7874 0.5842)
					(thickness 0.1524)
				)
				(justify left)
			)
		)
		(property "Value" ""
			(at 0 0 270)
			(layer "F.Fab")
			(effects
				(font
					(size 1.27 1.27)
				)
			)
		)
		(duplicate_pad_numbers_are_jumpers no)
		(fp_line
			(start -0.7874 0.4064)
			(end -0.7874 -0.4064)
			(stroke
				(width 0.1524)
				(type default)
			)
			(layer "F.SilkS")
		)
		(fp_line
			(start 0.7874 0.4064)
			(end -0.7874 0.4064)
			(stroke
				(width 0.1524)
				(type default)
			)
			(layer "F.SilkS")
		)
		(fp_line
			(start 0 0.381)
			(end 0 -0.381)
			(stroke
				(width 0.1524)
				(type default)
			)
			(layer "F.SilkS")
		)
		(fp_line
			(start -0.7874 -0.4064)
			(end 0.7874 -0.4064)
			(stroke
				(width 0.1524)
				(type default)
			)
			(layer "F.SilkS")
		)
		(fp_line
			(start 0.7874 -0.4064)
			(end 0.7874 0.4064)
			(stroke
				(width 0.1524)
				(type default)
			)
			(layer "F.SilkS")
		)
		(fp_poly
			(pts
				(xy -0.5334 0.254) (xy -0.635 0.254) (xy -0.635 0.2286) (xy -0.635 -0.254) (xy -0.5334 -0.254) (xy -0.5334 -0.2794)
				(xy 0.5334 -0.2794) (xy 0.5334 -0.254) (xy 0.635 -0.254) (xy 0.635 0.254) (xy 0.5334 0.254) (xy 0.5334 0.2794)
				(xy -0.508 0.2794) (xy -0.5334 0.2794)
			)
			(stroke
				(width 0)
				(type default)
			)
			(fill no)
			(layer "F.CrtYd")
		)
		(pad "1" smd rect
			(at 0.40005 0 270)
			(size 0.4572 0.508)
			(layers "F.Cu" "F.Mask" "F.Paste")
			(net "UART_T8_NODE1_RXD")
		)
		(pad "2" smd rect
			(at -0.40005 0 270)
			(size 0.4572 0.508)
			(layers "F.Cu" "F.Mask" "F.Paste")
			(net "GND")
		)
	)
	(footprint ""
		(layer "F.Cu")
		(at 91.17076 -15.804388 90)
		(property "Reference" "R189"
			(at 0.931164 0.263652 90)
			(unlocked yes)
			(layer "F.SilkS")
			(effects
				(font
					(size 0.7874 0.5842)
					(thickness 0.1524)
				)
				(justify left)
			)
		)
		(property "Value" ""
			(at 0 0 90)
			(layer "F.Fab")
			(effects
				(font
					(size 1.27 1.27)
				)
			)
		)
		(duplicate_pad_numbers_are_jumpers no)
		(fp_line
			(start 0.7874 -0.4064)
			(end 0.7874 0.4064)
			(stroke
				(width 0.1524)
				(type default)
			)
			(layer "F.SilkS")
		)
		(fp_line
			(start -0.7874 -0.4064)
			(end 0.7874 -0.4064)
			(stroke
				(width 0.1524)
				(type default)
			)
			(layer "F.SilkS")
		)
		(fp_line
			(start 0.7874 0.4064)
			(end -0.7874 0.4064)
			(stroke
				(width 0.1524)
				(type default)
			)
			(layer "F.SilkS")
		)
		(fp_line
			(start -0.7874 0.4064)
			(end -0.7874 -0.4064)
			(stroke
				(width 0.1524)
				(type default)
			)
			(layer "F.SilkS")
		)
		(fp_poly
			(pts
				(xy -0.508 0.2794) (xy -0.508 0.2286) (xy -0.635 0.2286) (xy -0.635 -0.254) (xy -0.5334 -0.254)
				(xy -0.5334 -0.2794) (xy 0.5334 -0.2794) (xy 0.5334 -0.254) (xy 0.635 -0.254) (xy 0.635 0.254) (xy 0.5334 0.254)
				(xy 0.5334 0.2794)
			)
			(stroke
				(width 0)
				(type default)
			)
			(fill no)
			(layer "F.CrtYd")
		)
		(pad "1" smd rect
			(at 0.40005 0 90)
			(size 0.4572 0.508)
			(layers "F.Cu" "F.Mask" "F.Paste")
			(net "LPC_CPU_NODE1_LAD3")
		)
		(pad "2" smd rect
			(at -0.40005 0 90)
			(size 0.4572 0.508)
			(layers "F.Cu" "F.Mask" "F.Paste")
			(net "LPC_CPU_TPM_LAD3")
		)
	)
	(footprint ""
		(layer "F.Cu")
		(at 138.729974 -20.799806 90)
		(property "Reference" "J8"
			(at -2.301494 -2.116328 90)
			(unlocked yes)
			(layer "F.SilkS")
			(effects
				(font
					(size 0.7874 0.5842)
					(thickness 0.1524)
				)
				(justify left)
			)
		)
		(property "Value" ""
			(at 0 0 90)
			(layer "F.Fab")
			(effects
				(font
					(size 1.27 1.27)
				)
			)
		)
		(duplicate_pad_numbers_are_jumpers no)
		(fp_line
			(start 2.54 -1.394968)
			(end 2.54 3.934968)
			(stroke
				(width 0.1524)
				(type default)
			)
			(layer "F.SilkS")
		)
		(fp_line
			(start -2.124964 -1.394968)
			(end -2.124964 3.934968)
			(stroke
				(width 0.124968)
				(type default)
			)
			(layer "F.SilkS")
		)
		(fp_line
			(start -2.249932 -1.394968)
			(end -2.249932 3.934968)
			(stroke
				(width 0.124968)
				(type default)
			)
			(layer "F.SilkS")
		)
		(fp_line
			(start -2.249932 -1.394968)
			(end -2.249932 3.934968)
			(stroke
				(width 0.124968)
				(type default)
			)
			(layer "F.SilkS")
		)
		(fp_line
			(start -2.3749 -1.394968)
			(end -2.3749 3.934968)
			(stroke
				(width 0.124968)
				(type default)
			)
			(layer "F.SilkS")
		)
		(fp_line
			(start -2.3749 -1.394968)
			(end -2.3749 3.934968)
			(stroke
				(width 0.124968)
				(type default)
			)
			(layer "F.SilkS")
		)
		(fp_line
			(start -2.500122 -1.394968)
			(end -2.500122 3.934968)
			(stroke
				(width 0.124968)
				(type default)
			)
			(layer "F.SilkS")
		)
		(fp_line
			(start -2.54 -1.394968)
			(end 2.54 -1.394968)
			(stroke
				(width 0.1524)
				(type default)
			)
			(layer "F.SilkS")
		)
		(fp_line
			(start -2.54 -1.394968)
			(end -2.54 3.934968)
			(stroke
				(width 0.1524)
				(type default)
			)
			(layer "F.SilkS")
		)
		(fp_line
			(start 2.54 3.934968)
			(end -2.54 3.934968)
			(stroke
				(width 0.1524)
				(type default)
			)
			(layer "F.SilkS")
		)
		(fp_line
			(start -1.500124 3.934968)
			(end -1.500124 -1.394968)
			(stroke
				(width 0.124968)
				(type default)
			)
			(layer "F.SilkS")
		)
		(fp_line
			(start -1.562608 3.934968)
			(end -1.562608 -1.394968)
			(stroke
				(width 0.124968)
				(type default)
			)
			(layer "F.SilkS")
		)
		(fp_line
			(start -1.625092 3.934968)
			(end -1.625092 -1.394968)
			(stroke
				(width 0.124968)
				(type default)
			)
			(layer "F.SilkS")
		)
		(fp_line
			(start -1.687576 3.934968)
			(end -1.687576 -1.394968)
			(stroke
				(width 0.124968)
				(type default)
			)
			(layer "F.SilkS")
		)
		(fp_line
			(start -1.75006 3.934968)
			(end -1.75006 -1.394968)
			(stroke
				(width 0.124968)
				(type default)
			)
			(layer "F.SilkS")
		)
		(fp_line
			(start -1.875028 3.934968)
			(end -1.875028 -1.394968)
			(stroke
				(width 0.124968)
				(type default)
			)
			(layer "F.SilkS")
		)
		(fp_line
			(start -1.937512 3.934968)
			(end -1.937512 -1.394968)
			(stroke
				(width 0.124968)
				(type default)
			)
			(layer "F.SilkS")
		)
		(fp_line
			(start -1.999996 3.934968)
			(end -1.999996 -1.394968)
			(stroke
				(width 0.124968)
				(type default)
			)
			(layer "F.SilkS")
		)
		(fp_line
			(start -2.06248 3.934968)
			(end -2.06248 -1.394968)
			(stroke
				(width 0.124968)
				(type default)
			)
			(layer "F.SilkS")
		)
		(fp_line
			(start -2.312416 3.934968)
			(end -2.312416 -1.394968)
			(stroke
				(width 0.124968)
				(type default)
			)
			(layer "F.SilkS")
		)
		(fp_line
			(start -2.54 3.934968)
			(end -2.54 -1.394968)
			(stroke
				(width 0.1524)
				(type default)
			)
			(layer "F.SilkS")
		)
		(fp_line
			(start -2.54 3.934968)
			(end -2.54 -1.394968)
			(stroke
				(width 0.1524)
				(type default)
			)
			(layer "F.SilkS")
		)
		(fp_poly
			(pts
				(xy -2.5908 0.0127) (xy -4.1656 0.4445) (xy -4.1656 -0.4445)
			)
			(stroke
				(width 0)
				(type default)
			)
			(fill yes)
			(layer "F.SilkS")
		)
		(fp_poly
			(pts
				(xy -0.8382 3.3782) (xy -0.8382 -0.8382) (xy 0.8382 -0.8382) (xy 0.8382 3.3782)
			)
			(stroke
				(width 0)
				(type default)
			)
			(fill no)
			(layer "B.CrtYd")
		)
		(fp_rect
			(start 2.54 3.934968)
			(end -2.54 -1.394968)
			(stroke
				(width 0)
				(type default)
			)
			(fill no)
			(layer "F.CrtYd")
		)
		(fp_line
			(start 2.54 -1.394968)
			(end 2.54 3.934968)
			(stroke
				(width 0.1)
				(type default)
			)
			(layer "F.Fab")
		)
		(fp_line
			(start -2.54 -1.394968)
			(end 2.54 -1.394968)
			(stroke
				(width 0.1)
				(type default)
			)
			(layer "F.Fab")
		)
		(fp_line
			(start 2.54 3.934968)
			(end -2.54 3.934968)
			(stroke
				(width 0.1)
				(type default)
			)
			(layer "F.Fab")
		)
		(fp_line
			(start -2.54 3.934968)
			(end -2.54 -1.394968)
			(stroke
				(width 0.1)
				(type default)
			)
			(layer "F.Fab")
		)
		(fp_poly
			(pts
				(xy -2.5908 0.0127) (xy -4.1656 0.4445) (xy -4.1656 -0.4445)
			)
			(stroke
				(width 0)
				(type default)
			)
			(fill yes)
			(layer "F.Fab")
		)
		(fp_text user "1"
			(at -3.208528 -0.965708 0)
			(unlocked yes)
			(layer "F.SilkS")
			(effects
				(font
					(size 0.635 0.4064)
					(thickness 0.1524)
				)
				(justify left)
			)
		)
		(fp_text user "2"
			(at -3.19278 1.975612 0)
			(unlocked yes)
			(layer "F.SilkS")
			(effects
				(font
					(size 0.635 0.4064)
					(thickness 0.1524)
				)
				(justify left)
			)
		)
		(fp_text user "1"
			(at 1.561846 0.507492 0)
			(unlocked yes)
			(layer "B.SilkS")
			(effects
				(font
					(size 0.7874 0.5842)
					(thickness 0.1524)
				)
				(justify left mirror)
			)
		)
		(fp_text user "2"
			(at 2.135124 2.927858 0)
			(unlocked yes)
			(layer "B.SilkS")
			(effects
				(font
					(size 0.7874 0.5842)
					(thickness 0.1524)
				)
				(justify left mirror)
			)
		)
		(fp_text user "1"
			(at -1.31953 -0.3302 180)
			(unlocked yes)
			(layer "B.Fab")
			(effects
				(font
					(size 0.7874 0.5842)
					(thickness 0.000001)
				)
				(justify left mirror)
			)
		)
		(fp_text user "2"
			(at -1.34493 2.3622 180)
			(unlocked yes)
			(layer "B.Fab")
			(effects
				(font
					(size 0.7874 0.5842)
					(thickness 0.000001)
				)
				(justify left mirror)
			)
		)
		(fp_text user "1"
			(at -3.114548 -0.2159 180)
			(unlocked yes)
			(layer "F.Fab")
			(effects
				(font
					(size 0.7874 0.5842)
					(thickness 0.000001)
				)
				(justify left)
			)
		)
		(fp_text user "2"
			(at -3.114548 2.8321 180)
			(unlocked yes)
			(layer "F.Fab")
			(effects
				(font
					(size 0.7874 0.5842)
					(thickness 0.000001)
				)
				(justify left)
			)
		)
		(pad "1" thru_hole rect
			(at 0 0 180)
			(size 1.5494 1.5494)
			(drill 1.0414)
			(layers "*.Cu" "*.Mask")
			(remove_unused_layers no)
			(net "GND")
			(clearance 0)
			(padstack
				(mode front_inner_back)
				(layer "Inner"
					(shape circle)
					(size 1.5494 1.5494)
					(clearance 0)
				)
				(layer "B.Cu"
					(shape rect)
					(size 1.5494 1.5494)
					(clearance 0)
				)
			)
		)
		(pad "2" thru_hole circle
			(at 0 2.54 180)
			(size 1.5494 1.5494)
			(drill 1.0414)
			(layers "*.Cu" "*.Mask")
			(remove_unused_layers no)
			(net "P5V_NODE1")
			(clearance 0)
		)
	)
)
